# T6G (Grand Teton) — schematic netlist excerpt (pin names and nets, part order shuffled) for the footprints in the layout excerpt that follows; sources: Cadence DE-HDL packaged netlist, KiCad conversion of 04192023_DAF0TMB3IC0_F0TG_MB_C_brd_V02_OCP.brd

C543  Q_CAP  0.1UF 10V 10% X7S  pkg C0201  page 279 : A = P0V9_CPU0_RT0_2A ; B = GND
C2  Q_CAP  0.1UF 25V 10% X7R  pkg 0402  page 160 : A = P3V3_AUX ; B = GND
R292  Q_RES  1K 1% CHIP  pkg 0402LF  page 87 : A = PWRGD_CHB_CPU0_DIMM ; B = PWRGD_CHAF_CPU0

(kicad_pcb
	(version 20260206)
	(generator "pcbnew")
	(generator_version "10.0")
	(general
		(thickness 1.6)
		(legacy_teardrops no)
	)
	(paper "A4")
	(title_block
		(title "04192023_DAF0TMB3IC0_F0TG_MB_C_brd_V02_OCP.brd")
		(comment 1 "Grand Teton / footprints 6454-6456 of 8354")
	)
	(layers
		(0 "F.Cu" signal "TOP")
		(4 "In1.Cu" signal "GND")
		(6 "In2.Cu" signal "IN1")
		(8 "In3.Cu" signal "GND1")
		(10 "In4.Cu" signal "IN2")
		(12 "In5.Cu" signal "GND2")
		(14 "In6.Cu" signal "IN3")
		(16 "In7.Cu" signal "GND3")
		(18 "In8.Cu" signal "VCC")
		(20 "In9.Cu" signal "VCC1")
		(22 "In10.Cu" signal "GND4")
		(24 "In11.Cu" signal "IN4")
		(26 "In12.Cu" signal "GND5")
		(28 "In13.Cu" signal "IN5")
		(30 "In14.Cu" signal "GND6")
		(32 "In15.Cu" signal "IN6")
		(34 "In16.Cu" signal "GND7")
		(2 "B.Cu" signal "BOTTOM")
		(9 "F.Adhes" user "F.Adhesive")
		(11 "B.Adhes" user "B.Adhesive")
		(13 "F.Paste" user "Package Geometry/Pastemask Top")
		(15 "B.Paste" user "Package Geometry/Pastemask Bottom")
		(5 "F.SilkS" user "Ref Des/Silkscreen Top")
		(7 "B.SilkS" user "Ref Des/Silkscreen Bottom")
		(1 "F.Mask" user "Board Geometry/Soldermask Top")
		(3 "B.Mask" user "Board Geometry/Soldermask Bottom")
		(17 "Dwgs.User" user "User.Drawings")
		(19 "Cmts.User" user "User.Comments")
		(21 "Eco1.User" user "User.Eco1")
		(23 "Eco2.User" user "User.Eco2")
		(25 "Edge.Cuts" user "Board Geometry/Outline")
		(27 "Margin" user)
		(31 "F.CrtYd" user "Package Geometry/Place Bound Top")
		(29 "B.CrtYd" user "Package Geometry/Place Bound Bottom")
		(35 "F.Fab" user "Ref Des/Assembly Top")
		(33 "B.Fab" user "Ref Des/Assembly Bottom")
	)
	(footprint ""
		(layer "B.Cu")
		(at 305.918362 -396.393162 -90)
		(property "Reference" "C543"
			(at 0 0 90)
			(layer "B.SilkS")
			(hide yes)
			(effects
				(font
					(size 1.27 1.27)
				)
				(justify mirror)
			)
		)
		(property "Value" ""
			(at 0 0 90)
			(layer "B.Fab")
			(effects
				(font
					(size 1.27 1.27)
				)
				(justify mirror)
			)
		)
		(duplicate_pad_numbers_are_jumpers no)
		(fp_line
			(start -0.299974 0.150114)
			(end 0.299974 0.150114)
			(stroke
				(width 0.1)
				(type default)
			)
			(layer "B.Fab")
		)
		(fp_line
			(start 0.299974 0.150114)
			(end 0.299974 -0.150114)
			(stroke
				(width 0.1)
				(type default)
			)
			(layer "B.Fab")
		)
		(fp_line
			(start -0.299974 -0.150114)
			(end -0.299974 0.150114)
			(stroke
				(width 0.1)
				(type default)
			)
			(layer "B.Fab")
		)
		(fp_line
			(start 0.299974 -0.150114)
			(end -0.299974 -0.150114)
			(stroke
				(width 0.1)
				(type default)
			)
			(layer "B.Fab")
		)
		(pad "1" smd rect
			(at 0.2667 0 90)
			(size 0.3048 0.381)
			(layers "B.Cu" "B.Mask" "B.Paste")
			(net "P0V9_CPU0_RT0_2A")
		)
		(pad "2" smd rect
			(at -0.2667 0 90)
			(size 0.3048 0.381)
			(layers "B.Cu" "B.Mask" "B.Paste")
			(net "GND")
		)
	)
	(footprint ""
		(layer "B.Cu")
		(at 295.478454 -190.94831 180)
		(property "Reference" "R292"
			(at 0 0 0)
			(layer "B.SilkS")
			(hide yes)
			(effects
				(font
					(size 1.27 1.27)
				)
				(justify mirror)
			)
		)
		(property "Value" ""
			(at 0 0 0)
			(layer "B.Fab")
			(effects
				(font
					(size 1.27 1.27)
				)
				(justify mirror)
			)
		)
		(duplicate_pad_numbers_are_jumpers no)
		(fp_line
			(start 0.7874 0.4064)
			(end 0.7874 -0.4064)
			(stroke
				(width 0.1524)
				(type default)
			)
			(layer "B.SilkS")
		)
		(fp_line
			(start 0.7874 -0.4064)
			(end -0.7874 -0.4064)
			(stroke
				(width 0.1524)
				(type default)
			)
			(layer "B.SilkS")
		)
		(fp_line
			(start -0.7874 0.4064)
			(end 0.7874 0.4064)
			(stroke
				(width 0.1524)
				(type default)
			)
			(layer "B.SilkS")
		)
		(fp_line
			(start -0.7874 -0.4064)
			(end -0.7874 0.4064)
			(stroke
				(width 0.1524)
				(type default)
			)
			(layer "B.SilkS")
		)
		(fp_line
			(start 0.67945 0.3048)
			(end 0.67945 -0.305054)
			(stroke
				(width 0.1)
				(type default)
			)
			(layer "B.Fab")
		)
		(fp_line
			(start 0.67945 -0.305054)
			(end 0.12065 -0.305054)
			(stroke
				(width 0.1)
				(type default)
			)
			(layer "B.Fab")
		)
		(fp_line
			(start 0.12065 0.3048)
			(end 0.67945 0.3048)
			(stroke
				(width 0.1)
				(type default)
			)
			(layer "B.Fab")
		)
		(fp_line
			(start 0.12065 0.2794)
			(end 0.12065 0.3048)
			(stroke
				(width 0.1)
				(type default)
			)
			(layer "B.Fab")
		)
		(fp_line
			(start 0.12065 -0.2794)
			(end -0.12065 -0.2794)
			(stroke
				(width 0.1)
				(type default)
			)
			(layer "B.Fab")
		)
		(fp_line
			(start 0.12065 -0.305054)
			(end 0.12065 -0.2794)
			(stroke
				(width 0.1)
				(type default)
			)
			(layer "B.Fab")
		)
		(fp_line
			(start -0.120396 0.3048)
			(end -0.120396 0.2794)
			(stroke
				(width 0.1)
				(type default)
			)
			(layer "B.Fab")
		)
		(fp_line
			(start -0.120396 0.2794)
			(end 0.12065 0.2794)
			(stroke
				(width 0.1)
				(type default)
			)
			(layer "B.Fab")
		)
		(fp_line
			(start -0.12065 -0.2794)
			(end -0.12065 -0.3048)
			(stroke
				(width 0.1)
				(type default)
			)
			(layer "B.Fab")
		)
		(fp_line
			(start -0.12065 -0.3048)
			(end -0.67945 -0.3048)
			(stroke
				(width 0.1)
				(type default)
			)
			(layer "B.Fab")
		)
		(fp_line
			(start -0.67945 0.3048)
			(end -0.120396 0.3048)
			(stroke
				(width 0.1)
				(type default)
			)
			(layer "B.Fab")
		)
		(fp_line
			(start -0.67945 -0.3048)
			(end -0.67945 0.3048)
			(stroke
				(width 0.1)
				(type default)
			)
			(layer "B.Fab")
		)
		(pad "1" smd circle
			(at 0.40005 0)
			(size 0 0)
			(layers "B.Cu" "B.Mask" "B.Paste")
			(net "PWRGD_CHB_CPU0_DIMM")
		)
		(pad "2" smd circle
			(at -0.40005 0)
			(size 0 0)
			(layers "B.Cu" "B.Mask" "B.Paste")
			(net "PWRGD_CHAF_CPU0")
		)
	)
	(footprint ""
		(layer "B.Cu")
		(at 233.013758 -224.397316 -90)
		(property "Reference" "C2"
			(at 0 0 90)
			(layer "B.SilkS")
			(hide yes)
			(effects
				(font
					(size 1.27 1.27)
				)
				(justify mirror)
			)
		)
		(property "Value" ""
			(at 0 0 90)
			(layer "B.Fab")
			(effects
				(font
					(size 1.27 1.27)
				)
				(justify mirror)
			)
		)
		(duplicate_pad_numbers_are_jumpers no)
		(fp_line
			(start -0.7874 0.4064)
			(end 0.7874 0.4064)
			(stroke
				(width 0.1524)
				(type default)
			)
			(layer "B.SilkS")
		)
		(fp_line
			(start 0.7874 0.4064)
			(end 0.7874 -0.4064)
			(stroke
				(width 0.1524)
				(type default)
			)
			(layer "B.SilkS")
		)
		(fp_line
			(start -0.7874 -0.4064)
			(end -0.7874 0.4064)
			(stroke
				(width 0.1524)
				(type default)
			)
			(layer "B.SilkS")
		)
		(fp_line
			(start 0.7874 -0.4064)
			(end -0.7874 -0.4064)
			(stroke
				(width 0.1524)
				(type default)
			)
			(layer "B.SilkS")
		)
		(fp_line
			(start -0.67945 0.3048)
			(end -0.120396 0.3048)
			(stroke
				(width 0.1)
				(type default)
			)
			(layer "B.Fab")
		)
		(fp_line
			(start -0.120396 0.3048)
			(end -0.120396 0.2794)
			(stroke
				(width 0.1)
				(type default)
			)
			(layer "B.Fab")
		)
		(fp_line
			(start 0.12065 0.3048)
			(end 0.67945 0.3048)
			(stroke
				(width 0.1)
				(type default)
			)
			(layer "B.Fab")
		)
		(fp_line
			(start 0.67945 0.3048)
			(end 0.67945 -0.305054)
			(stroke
				(width 0.1)
				(type default)
			)
			(layer "B.Fab")
		)
		(fp_line
			(start -0.120396 0.2794)
			(end 0.12065 0.2794)
			(stroke
				(width 0.1)
				(type default)
			)
			(layer "B.Fab")
		)
		(fp_line
			(start 0.12065 0.2794)
			(end 0.12065 0.3048)
			(stroke
				(width 0.1)
				(type default)
			)
			(layer "B.Fab")
		)
		(fp_line
			(start -0.12065 -0.2794)
			(end -0.12065 -0.3048)
			(stroke
				(width 0.1)
				(type default)
			)
			(layer "B.Fab")
		)
		(fp_line
			(start 0.12065 -0.2794)
			(end -0.12065 -0.2794)
			(stroke
				(width 0.1)
				(type default)
			)
			(layer "B.Fab")
		)
		(fp_line
			(start -0.67945 -0.3048)
			(end -0.67945 0.3048)
			(stroke
				(width 0.1)
				(type default)
			)
			(layer "B.Fab")
		)
		(fp_line
			(start -0.12065 -0.3048)
			(end -0.67945 -0.3048)
			(stroke
				(width 0.1)
				(type default)
			)
			(layer "B.Fab")
		)
		(fp_line
			(start 0.12065 -0.305054)
			(end 0.12065 -0.2794)
			(stroke
				(width 0.1)
				(type default)
			)
			(layer "B.Fab")
		)
		(fp_line
			(start 0.67945 -0.305054)
			(end 0.12065 -0.305054)
			(stroke
				(width 0.1)
				(type default)
			)
			(layer "B.Fab")
		)
		(pad "1" smd circle
			(at 0.40005 0 90)
			(size 0 0)
			(layers "B.Cu" "B.Mask" "B.Paste")
			(net "P3V3_AUX")
		)
		(pad "2" smd circle
			(at -0.40005 0 90)
			(size 0 0)
			(layers "B.Cu" "B.Mask" "B.Paste")
			(net "GND")
		)
	)
)
